FILE_TYPE = MULTI_PHYS_TABLE;
PART 'SCONN11_H67026001'
{====================================================================================================================================================================================================================}
:PACK_TYPE|MATERIAL  |PART_NUMBER      = EnvComp |PART_NUMBER   |JEDEC_TYPE           |DESCRIPTION                    |CLASS  |COMPONENT_TYPE  |HEIGHT      | LPID   | SPEED_URL | Status |RPL| AML | Bus_Unit | Days;
{====================================================================================================================================================================================================================}
'SM'      | 'CONN'   | 'H67026-001'(!) = ''      | 'H67026-001' | 'SCONN11_H67026001' | 'CONN,BTB,11P,RCP,VT,4MM,1MM' | 'IO'  | 'SMTCONN'      | '0.164 IN' | '3814' | 'http://speed.intel.com:8081/speed/module/pdm/item/pdm_item_detail_direct.asp?item_cde=H67026-001&item_rev=01&url_param=unused' | '' | '' | '' | '' | '' 
'SM'      | 'EMPTY'  | 'H67026-001'(!) = ''      | 'H67026-001' | 'SCONN11_H67026001' | 'CONN,BTB,11P,RCP,VT,4MM,1MM' | 'IO'  | 'SMTCONN'      | '0.164 IN' | '3814' | 'http://speed.intel.com:8081/speed/module/pdm/item/pdm_item_detail_direct.asp?item_cde=H67026-001&item_rev=01&url_param=unused' | '' | '' | '' | '' | '' 
END_PART
END.
